(kicad_pcb
	(version 20260206)
	(generator "pcbnew")
	(generator_version "10.0")
	(general
		(thickness 1.6)
		(legacy_teardrops no)
	)
	(paper "A4")
	(title_block
		(title "Bryce Canyon_IOM_M2_16342-2_OCP.brd")
		(comment 1 "Bryce Canyon / footprints 903-909 of 1146")
	)
	(layers
		(0 "F.Cu" signal "TOP")
		(4 "In1.Cu" signal "L2GND")
		(6 "In2.Cu" signal "L3")
		(8 "In3.Cu" signal "L4VCC")
		(10 "In4.Cu" signal "L5VCC")
		(12 "In5.Cu" signal "L6")
		(14 "In6.Cu" signal "L7GND")
		(2 "B.Cu" signal "BOTTOM")
		(9 "F.Adhes" user "F.Adhesive")
		(11 "B.Adhes" user "B.Adhesive")
		(13 "F.Paste" user "Package Geometry/Pastemask Top")
		(15 "B.Paste" user "Package Geometry/Pastemask Bottom")
		(5 "F.SilkS" user "Ref Des/Silkscreen Top")
		(7 "B.SilkS" user "Ref Des/Silkscreen Bottom")
		(1 "F.Mask" user "Board Geometry/Soldermask Top")
		(3 "B.Mask" user "Board Geometry/Soldermask Bottom")
		(17 "Dwgs.User" user "User.Drawings")
		(19 "Cmts.User" user "User.Comments")
		(21 "Eco1.User" user "User.Eco1")
		(23 "Eco2.User" user "User.Eco2")
		(25 "Edge.Cuts" user "Board Geometry/Outline")
		(27 "Margin" user)
		(31 "F.CrtYd" user "Package Geometry/Place Bound Top")
		(29 "B.CrtYd" user "Package Geometry/Place Bound Bottom")
		(35 "F.Fab" user "Ref Des/Assembly Top")
		(33 "B.Fab" user "Ref Des/Assembly Bottom")
	)
	(footprint ""
		(layer "B.Cu")
		(at 95.939356 -158.69412 180)
		(property "Reference" "C8"
			(at 0 0 0)
			(layer "B.SilkS")
			(hide yes)
			(effects
				(font
					(size 1.27 1.27)
				)
				(justify mirror)
			)
		)
		(property "Value" "SC1U16V3KX-5GP"
			(at 0 -2.8194 180)
			(unlocked yes)
			(layer "B.Fab")
			(hide yes)
			(effects
				(font
					(size 1.016 1.016)
					(thickness 0.1524)
				)
				(justify mirror)
			)
		)
		(property "Device Type" "C603H36"
			(at 0 -4.3434 180)
			(unlocked yes)
			(layer "B.Fab")
			(hide yes)
			(effects
				(font
					(size 1.016 1.016)
					(thickness 0.1524)
				)
				(justify mirror)
			)
		)
		(duplicate_pad_numbers_are_jumpers no)
		(fp_line
			(start -0.508 0)
			(end 0.508 0)
			(stroke
				(width 0.2032)
				(type default)
			)
			(layer "B.SilkS")
		)
		(fp_rect
			(start 0.5842 1.3335)
			(end -0.5842 -1.3335)
			(stroke
				(width 0)
				(type default)
			)
			(fill no)
			(layer "B.CrtYd")
		)
		(fp_rect
			(start 0.5842 1.3335)
			(end -0.5842 -1.3335)
			(stroke
				(width 0)
				(type default)
			)
			(fill no)
			(layer "B.Fab")
		)
		(pad "1" smd custom
			(at 0 -0.762)
			(size 0.2159 0.2159)
			(layers "B.Cu" "B.Mask" "B.Paste")
			(net "USB_RESET_N")
			(options
				(clearance outline)
				(anchor circle)
			)
			(primitives
				(gr_poly
					(pts
						(arc
							(start -0.3302 0.4318)
							(mid -0.402042 0.402042)
							(end -0.4318 0.3302)
						)
						(arc
							(start -0.4318 -0.3302)
							(mid -0.402042 -0.402042)
							(end -0.3302 -0.4318)
						)
						(arc
							(start 0.3302 -0.4318)
							(mid 0.402042 -0.402042)
							(end 0.4318 -0.3302)
						)
						(arc
							(start 0.4318 0.3302)
							(mid 0.402042 0.402042)
							(end 0.3302 0.4318)
						)
					)
					(width 0)
					(fill yes)
				)
			)
		)
		(pad "2" smd custom
			(at 0 0.762)
			(size 0.2159 0.2159)
			(layers "B.Cu" "B.Mask" "B.Paste")
			(net "GND")
			(options
				(clearance outline)
				(anchor circle)
			)
			(primitives
				(gr_poly
					(pts
						(arc
							(start -0.3302 0.4318)
							(mid -0.402042 0.402042)
							(end -0.4318 0.3302)
						)
						(arc
							(start -0.4318 -0.3302)
							(mid -0.402042 -0.402042)
							(end -0.3302 -0.4318)
						)
						(arc
							(start 0.3302 -0.4318)
							(mid 0.402042 -0.402042)
							(end 0.4318 -0.3302)
						)
						(arc
							(start 0.4318 0.3302)
							(mid 0.402042 0.402042)
							(end 0.3302 0.4318)
						)
					)
					(width 0)
					(fill yes)
				)
			)
		)
	)
	(footprint ""
		(layer "B.Cu")
		(at 31.1404 -152.0444)
		(property "Reference" "L3"
			(at 0 0 0)
			(layer "B.SilkS")
			(hide yes)
			(effects
				(font
					(size 1.27 1.27)
				)
				(justify mirror)
			)
		)
		(property "Value" "MMZ2012S601ATA1N-GP"
			(at 0 -4.2418 0)
			(unlocked yes)
			(layer "B.Fab")
			(hide yes)
			(effects
				(font
					(size 1.016 1.016)
					(thickness 0.1524)
				)
				(justify mirror)
			)
		)
		(property "Device Type" "L805H42"
			(at 0 -5.7912 0)
			(unlocked yes)
			(layer "B.Fab")
			(hide yes)
			(effects
				(font
					(size 1.016 1.016)
					(thickness 0.1524)
				)
				(justify mirror)
			)
		)
		(duplicate_pad_numbers_are_jumpers no)
		(fp_line
			(start -0.889 -1.7018)
			(end -0.889 1.7018)
			(stroke
				(width 0.1524)
				(type default)
			)
			(layer "B.SilkS")
		)
		(fp_line
			(start -0.889 1.7018)
			(end 0.889 1.7018)
			(stroke
				(width 0.1524)
				(type default)
			)
			(layer "B.SilkS")
		)
		(fp_line
			(start 0.889 -1.7018)
			(end -0.889 -1.7018)
			(stroke
				(width 0.1524)
				(type default)
			)
			(layer "B.SilkS")
		)
		(fp_line
			(start 0.889 1.7018)
			(end 0.889 -1.7018)
			(stroke
				(width 0.1524)
				(type default)
			)
			(layer "B.SilkS")
		)
		(fp_rect
			(start 0.9652 1.778)
			(end -0.9652 -1.778)
			(stroke
				(width 0)
				(type default)
			)
			(fill no)
			(layer "B.CrtYd")
		)
		(fp_rect
			(start 0.9652 1.778)
			(end -0.9652 -1.778)
			(stroke
				(width 0)
				(type default)
			)
			(fill no)
			(layer "B.Fab")
		)
		(pad "1" smd rect
			(at 0 -0.9652 180)
			(size 1.397 1.143)
			(layers "B.Cu" "B.Mask" "B.Paste")
			(net "P3V3_STBY")
		)
		(pad "2" smd rect
			(at 0 0.9652 180)
			(size 1.397 1.143)
			(layers "B.Cu" "B.Mask" "B.Paste")
			(net "MPLLAV33")
		)
	)
	(footprint ""
		(layer "B.Cu")
		(at 20.582128 -131.007358 180)
		(property "Reference" "R253"
			(at 0 0 0)
			(layer "B.SilkS")
			(hide yes)
			(effects
				(font
					(size 1.27 1.27)
				)
				(justify mirror)
			)
		)
		(property "Value" "120R2F-GP"
			(at -0.064008 -3.993896 180)
			(unlocked yes)
			(layer "B.Fab")
			(hide yes)
			(effects
				(font
					(size 1.016 1.016)
					(thickness 0.1524)
				)
				(justify mirror)
			)
		)
		(property "Device Type" "R402H16"
			(at -0.064008 -5.517896 180)
			(unlocked yes)
			(layer "B.Fab")
			(hide yes)
			(effects
				(font
					(size 1.016 1.016)
					(thickness 0.1524)
				)
				(justify mirror)
			)
		)
		(duplicate_pad_numbers_are_jumpers no)
		(fp_line
			(start 0.508 -0.9398)
			(end 0.508 0.9398)
			(stroke
				(width 0.1524)
				(type default)
			)
			(layer "B.SilkS")
		)
		(fp_line
			(start -0.508 -0.9398)
			(end 0.508 -0.9398)
			(stroke
				(width 0.1524)
				(type default)
			)
			(layer "B.SilkS")
		)
		(fp_rect
			(start 0.508 0.9398)
			(end -0.508 -0.9398)
			(stroke
				(width 0)
				(type default)
			)
			(fill no)
			(layer "B.CrtYd")
		)
		(fp_rect
			(start 0.508 0.9398)
			(end -0.508 -0.9398)
			(stroke
				(width 0)
				(type default)
			)
			(fill no)
			(layer "B.Fab")
		)
		(pad "1" smd custom
			(at 0 -0.4445)
			(size 0.1397 0.1397)
			(layers "B.Cu" "B.Mask" "B.Paste")
			(net "MEMA_9")
			(options
				(clearance outline)
				(anchor circle)
			)
			(primitives
				(gr_poly
					(pts
						(arc
							(start -0.1778 0.2794)
							(mid -0.249642 0.249642)
							(end -0.2794 0.1778)
						)
						(arc
							(start -0.2794 -0.1778)
							(mid -0.249642 -0.249642)
							(end -0.1778 -0.2794)
						)
						(arc
							(start 0.1778 -0.2794)
							(mid 0.249642 -0.249642)
							(end 0.2794 -0.1778)
						)
						(arc
							(start 0.2794 0.1778)
							(mid 0.249642 0.249642)
							(end 0.1778 0.2794)
						)
					)
					(width 0)
					(fill yes)
				)
			)
		)
		(pad "2" smd custom
			(at 0 0.4445)
			(size 0.1397 0.1397)
			(layers "B.Cu" "B.Mask" "B.Paste")
			(net "P1V2_STBY")
			(options
				(clearance outline)
				(anchor circle)
			)
			(primitives
				(gr_poly
					(pts
						(arc
							(start -0.1778 0.2794)
							(mid -0.249642 0.249642)
							(end -0.2794 0.1778)
						)
						(arc
							(start -0.2794 -0.1778)
							(mid -0.249642 -0.249642)
							(end -0.1778 -0.2794)
						)
						(arc
							(start 0.1778 -0.2794)
							(mid 0.249642 -0.249642)
							(end 0.2794 -0.1778)
						)
						(arc
							(start 0.2794 0.1778)
							(mid 0.249642 0.249642)
							(end 0.1778 0.2794)
						)
					)
					(width 0)
					(fill yes)
				)
			)
		)
	)
	(footprint ""
		(layer "B.Cu")
		(at 44.4246 -128.2192 180)
		(property "Reference" "R371"
			(at 0 0 0)
			(layer "B.SilkS")
			(hide yes)
			(effects
				(font
					(size 1.27 1.27)
				)
				(justify mirror)
			)
		)
		(property "Value" "4K7R2F-GP"
			(at -0.064008 -3.993896 180)
			(unlocked yes)
			(layer "B.Fab")
			(hide yes)
			(effects
				(font
					(size 1.016 1.016)
					(thickness 0.1524)
				)
				(justify mirror)
			)
		)
		(property "Device Type" "R402H16"
			(at -0.064008 -5.517896 180)
			(unlocked yes)
			(layer "B.Fab")
			(hide yes)
			(effects
				(font
					(size 1.016 1.016)
					(thickness 0.1524)
				)
				(justify mirror)
			)
		)
		(duplicate_pad_numbers_are_jumpers no)
		(fp_line
			(start 0.508 -0.9398)
			(end 0.508 0.9398)
			(stroke
				(width 0.1524)
				(type default)
			)
			(layer "B.SilkS")
		)
		(fp_line
			(start -0.508 -0.9398)
			(end 0.508 -0.9398)
			(stroke
				(width 0.1524)
				(type default)
			)
			(layer "B.SilkS")
		)
		(fp_rect
			(start 0.508 0.9398)
			(end -0.508 -0.9398)
			(stroke
				(width 0)
				(type default)
			)
			(fill no)
			(layer "B.CrtYd")
		)
		(fp_rect
			(start 0.508 0.9398)
			(end -0.508 -0.9398)
			(stroke
				(width 0)
				(type default)
			)
			(fill no)
			(layer "B.Fab")
		)
		(pad "1" smd custom
			(at 0 -0.4445)
			(size 0.1397 0.1397)
			(layers "B.Cu" "B.Mask" "B.Paste")
			(net "P3V3_STBY")
			(options
				(clearance outline)
				(anchor circle)
			)
			(primitives
				(gr_poly
					(pts
						(arc
							(start -0.1778 0.2794)
							(mid -0.249642 0.249642)
							(end -0.2794 0.1778)
						)
						(arc
							(start -0.2794 -0.1778)
							(mid -0.249642 -0.249642)
							(end -0.1778 -0.2794)
						)
						(arc
							(start 0.1778 -0.2794)
							(mid 0.249642 -0.249642)
							(end 0.2794 -0.1778)
						)
						(arc
							(start 0.2794 0.1778)
							(mid 0.249642 0.249642)
							(end 0.1778 0.2794)
						)
					)
					(width 0)
					(fill yes)
				)
			)
		)
		(pad "2" smd custom
			(at 0 0.4445)
			(size 0.1397 0.1397)
			(layers "B.Cu" "B.Mask" "B.Paste")
			(net "BMC_SPI_MISO")
			(options
				(clearance outline)
				(anchor circle)
			)
			(primitives
				(gr_poly
					(pts
						(arc
							(start -0.1778 0.2794)
							(mid -0.249642 0.249642)
							(end -0.2794 0.1778)
						)
						(arc
							(start -0.2794 -0.1778)
							(mid -0.249642 -0.249642)
							(end -0.1778 -0.2794)
						)
						(arc
							(start 0.1778 -0.2794)
							(mid 0.249642 -0.249642)
							(end 0.2794 -0.1778)
						)
						(arc
							(start 0.2794 0.1778)
							(mid 0.249642 0.249642)
							(end 0.1778 0.2794)
						)
					)
					(width 0)
					(fill yes)
				)
			)
		)
	)
	(footprint ""
		(layer "B.Cu")
		(at 90.084148 -132.396484)
		(property "Reference" "C503"
			(at 0 0 0)
			(layer "B.SilkS")
			(hide yes)
			(effects
				(font
					(size 1.27 1.27)
				)
				(justify mirror)
			)
		)
		(property "Value" "SCD1U16V2KX-3GP"
			(at -1.1811 -2.7051 0)
			(unlocked yes)
			(layer "B.Fab")
			(hide yes)
			(effects
				(font
					(size 1.016 1.016)
					(thickness 0.1524)
				)
				(justify mirror)
			)
		)
		(property "Device Type" "C402H22"
			(at -1.181354 -4.2291 0)
			(unlocked yes)
			(layer "B.Fab")
			(hide yes)
			(effects
				(font
					(size 1.016 1.016)
					(thickness 0.1524)
				)
				(justify mirror)
			)
		)
		(duplicate_pad_numbers_are_jumpers no)
		(fp_rect
			(start 0.4318 0.9525)
			(end -0.4318 -0.9525)
			(stroke
				(width 0)
				(type default)
			)
			(fill no)
			(layer "B.CrtYd")
		)
		(fp_rect
			(start 0.4318 0.9525)
			(end -0.4318 -0.9525)
			(stroke
				(width 0)
				(type default)
			)
			(fill no)
			(layer "B.Fab")
		)
		(pad "1" smd custom
			(at 0 -0.4445 180)
			(size 0.1524 0.1524)
			(layers "B.Cu" "B.Mask" "B.Paste")
			(net "P3V3_STBY")
			(options
				(clearance outline)
				(anchor circle)
			)
			(primitives
				(gr_poly
					(pts
						(arc
							(start 0.3048 0.2032)
							(mid 0.275042 0.275042)
							(end 0.2032 0.3048)
						)
						(arc
							(start -0.2032 0.3048)
							(mid -0.275042 0.275042)
							(end -0.3048 0.2032)
						)
						(arc
							(start -0.3048 -0.2032)
							(mid -0.275042 -0.275042)
							(end -0.2032 -0.3048)
						)
						(arc
							(start 0.2032 -0.3048)
							(mid 0.275042 -0.275042)
							(end 0.3048 -0.2032)
						)
					)
					(width 0)
					(fill yes)
				)
			)
		)
		(pad "2" smd custom
			(at 0 0.4445 180)
			(size 0.1524 0.1524)
			(layers "B.Cu" "B.Mask" "B.Paste")
			(net "GND")
			(options
				(clearance outline)
				(anchor circle)
			)
			(primitives
				(gr_poly
					(pts
						(arc
							(start 0.3048 0.2032)
							(mid 0.275042 0.275042)
							(end 0.2032 0.3048)
						)
						(arc
							(start -0.2032 0.3048)
							(mid -0.275042 0.275042)
							(end -0.3048 0.2032)
						)
						(arc
							(start -0.3048 -0.2032)
							(mid -0.275042 -0.275042)
							(end -0.2032 -0.3048)
						)
						(arc
							(start 0.2032 -0.3048)
							(mid 0.275042 -0.275042)
							(end 0.3048 -0.2032)
						)
					)
					(width 0)
					(fill yes)
				)
			)
		)
	)
	(footprint ""
		(layer "B.Cu")
		(at 24.456898 -145.973546)
		(property "Reference" "C72"
			(at 0 0 0)
			(layer "B.SilkS")
			(hide yes)
			(effects
				(font
					(size 1.27 1.27)
				)
				(justify mirror)
			)
		)
		(property "Value" "SCD1U16V2KX-3GP"
			(at -1.1811 -2.7051 0)
			(unlocked yes)
			(layer "B.Fab")
			(hide yes)
			(effects
				(font
					(size 1.016 1.016)
					(thickness 0.1524)
				)
				(justify mirror)
			)
		)
		(property "Device Type" "C402H22"
			(at -1.1811 -4.2291 0)
			(unlocked yes)
			(layer "B.Fab")
			(hide yes)
			(effects
				(font
					(size 1.016 1.016)
					(thickness 0.1524)
				)
				(justify mirror)
			)
		)
		(duplicate_pad_numbers_are_jumpers no)
		(fp_rect
			(start 0.4318 0.9525)
			(end -0.4318 -0.9525)
			(stroke
				(width 0)
				(type default)
			)
			(fill no)
			(layer "B.CrtYd")
		)
		(fp_rect
			(start 0.4318 0.9525)
			(end -0.4318 -0.9525)
			(stroke
				(width 0)
				(type default)
			)
			(fill no)
			(layer "B.Fab")
		)
		(pad "1" smd custom
			(at 0 -0.4445 180)
			(size 0.1524 0.1524)
			(layers "B.Cu" "B.Mask" "B.Paste")
			(net "GND")
			(options
				(clearance outline)
				(anchor circle)
			)
			(primitives
				(gr_poly
					(pts
						(arc
							(start 0.3048 0.2032)
							(mid 0.275042 0.275042)
							(end 0.2032 0.3048)
						)
						(arc
							(start -0.2032 0.3048)
							(mid -0.275042 0.275042)
							(end -0.3048 0.2032)
						)
						(arc
							(start -0.3048 -0.2032)
							(mid -0.275042 -0.275042)
							(end -0.2032 -0.3048)
						)
						(arc
							(start 0.2032 -0.3048)
							(mid 0.275042 -0.275042)
							(end 0.3048 -0.2032)
						)
					)
					(width 0)
					(fill yes)
				)
			)
		)
		(pad "2" smd custom
			(at 0 0.4445 180)
			(size 0.1524 0.1524)
			(layers "B.Cu" "B.Mask" "B.Paste")
			(net "P1V2_STBY")
			(options
				(clearance outline)
				(anchor circle)
			)
			(primitives
				(gr_poly
					(pts
						(arc
							(start 0.3048 0.2032)
							(mid 0.275042 0.275042)
							(end 0.2032 0.3048)
						)
						(arc
							(start -0.2032 0.3048)
							(mid -0.275042 0.275042)
							(end -0.3048 0.2032)
						)
						(arc
							(start -0.3048 -0.2032)
							(mid -0.275042 -0.275042)
							(end -0.2032 -0.3048)
						)
						(arc
							(start 0.2032 -0.3048)
							(mid 0.275042 -0.275042)
							(end 0.3048 -0.2032)
						)
					)
					(width 0)
					(fill yes)
				)
			)
		)
	)
	(footprint ""
		(layer "B.Cu")
		(at 10.193528 -132.402834 90)
		(property "Reference" "R237"
			(at 0 0 90)
			(layer "B.SilkS")
			(hide yes)
			(effects
				(font
					(size 1.27 1.27)
				)
				(justify mirror)
			)
		)
		(property "Value" "120R2F-GP"
			(at -0.064008 -3.993896 90)
			(unlocked yes)
			(layer "B.Fab")
			(hide yes)
			(effects
				(font
					(size 1.016 1.016)
					(thickness 0.1524)
				)
				(justify mirror)
			)
		)
		(property "Device Type" "R402H16"
			(at -0.064008 -5.517896 90)
			(unlocked yes)
			(layer "B.Fab")
			(hide yes)
			(effects
				(font
					(size 1.016 1.016)
					(thickness 0.1524)
				)
				(justify mirror)
			)
		)
		(duplicate_pad_numbers_are_jumpers no)
		(fp_line
			(start 0.508 -0.9398)
			(end 0.508 0.9398)
			(stroke
				(width 0.1524)
				(type default)
			)
			(layer "B.SilkS")
		)
		(fp_line
			(start -0.508 -0.9398)
			(end 0.508 -0.9398)
			(stroke
				(width 0.1524)
				(type default)
			)
			(layer "B.SilkS")
		)
		(fp_rect
			(start 0.508 0.9398)
			(end -0.508 -0.9398)
			(stroke
				(width 0)
				(type default)
			)
			(fill no)
			(layer "B.CrtYd")
		)
		(fp_rect
			(start 0.508 0.9398)
			(end -0.508 -0.9398)
			(stroke
				(width 0)
				(type default)
			)
			(fill no)
			(layer "B.Fab")
		)
		(pad "1" smd custom
			(at 0 -0.4445 270)
			(size 0.1397 0.1397)
			(layers "B.Cu" "B.Mask" "B.Paste")
			(net "GND")
			(options
				(clearance outline)
				(anchor circle)
			)
			(primitives
				(gr_poly
					(pts
						(arc
							(start -0.1778 0.2794)
							(mid -0.249642 0.249642)
							(end -0.2794 0.1778)
						)
						(arc
							(start -0.2794 -0.1778)
							(mid -0.249642 -0.249642)
							(end -0.1778 -0.2794)
						)
						(arc
							(start 0.1778 -0.2794)
							(mid 0.249642 -0.249642)
							(end 0.2794 -0.1778)
						)
						(arc
							(start 0.2794 0.1778)
							(mid 0.249642 0.249642)
							(end 0.1778 0.2794)
						)
					)
					(width 0)
					(fill yes)
				)
			)
		)
		(pad "2" smd custom
			(at 0 0.4445 270)
			(size 0.1397 0.1397)
			(layers "B.Cu" "B.Mask" "B.Paste")
			(net "MEMA_2")
			(options
				(clearance outline)
				(anchor circle)
			)
			(primitives
				(gr_poly
					(pts
						(arc
							(start -0.1778 0.2794)
							(mid -0.249642 0.249642)
							(end -0.2794 0.1778)
						)
						(arc
							(start -0.2794 -0.1778)
							(mid -0.249642 -0.249642)
							(end -0.1778 -0.2794)
						)
						(arc
							(start 0.1778 -0.2794)
							(mid 0.249642 -0.249642)
							(end 0.2794 -0.1778)
						)
						(arc
							(start 0.2794 0.1778)
							(mid 0.249642 0.249642)
							(end 0.1778 0.2794)
						)
					)
					(width 0)
					(fill yes)
				)
			)
		)
	)
)
